(kicad_pcb
	(version 20260206)
	(generator "pcbnew")
	(generator_version "10.0")
	(general
		(thickness 1.6)
		(legacy_teardrops no)
	)
	(paper "A4")
	(title_block
		(title "baseboard — 13948-1b.1110WZS1818.brd")
		(comment 1 "Honey Badger (Wiwynn) / footprints 2270-2276 of 2523")
	)
	(layers
		(0 "F.Cu" signal "TOP")
		(4 "In1.Cu" signal "L2GND")
		(6 "In2.Cu" signal "L3")
		(8 "In3.Cu" signal "L4VCC")
		(10 "In4.Cu" signal "L5VCC")
		(12 "In5.Cu" signal "L6")
		(14 "In6.Cu" signal "L7GND")
		(2 "B.Cu" signal "BOTTOM")
		(9 "F.Adhes" user "F.Adhesive")
		(11 "B.Adhes" user "B.Adhesive")
		(13 "F.Paste" user "Package Geometry/Pastemask Top")
		(15 "B.Paste" user "Package Geometry/Pastemask Bottom")
		(5 "F.SilkS" user "Ref Des/Silkscreen Top")
		(7 "B.SilkS" user "Ref Des/Silkscreen Bottom")
		(1 "F.Mask" user "Board Geometry/Soldermask Top")
		(3 "B.Mask" user "Board Geometry/Soldermask Bottom")
		(17 "Dwgs.User" user "User.Drawings")
		(19 "Cmts.User" user "User.Comments")
		(21 "Eco1.User" user "User.Eco1")
		(23 "Eco2.User" user "User.Eco2")
		(25 "Edge.Cuts" user "Board Geometry/Outline")
		(27 "Margin" user)
		(31 "F.CrtYd" user "Package Geometry/Place Bound Top")
		(29 "B.CrtYd" user "Package Geometry/Place Bound Bottom")
		(35 "F.Fab" user "Ref Des/Assembly Top")
		(33 "B.Fab" user "Ref Des/Assembly Bottom")
	)
	(footprint ""
		(layer "B.Cu")
		(at 102.389686 -55.31612 180)
		(property "Reference" "SC1012"
			(at 0 0 0)
			(layer "B.SilkS")
			(hide yes)
			(effects
				(font
					(size 1.27 1.27)
				)
				(justify mirror)
			)
		)
		(property "Value" "SC1KP50V2KX-1GP"
			(at -1.1811 -2.7051 180)
			(unlocked yes)
			(layer "B.Fab")
			(hide yes)
			(effects
				(font
					(size 1.016 1.016)
					(thickness 0.1524)
				)
				(justify mirror)
			)
		)
		(property "Device Type" "C402H22"
			(at -1.1811 -4.2291 180)
			(unlocked yes)
			(layer "B.Fab")
			(hide yes)
			(effects
				(font
					(size 1.016 1.016)
					(thickness 0.1524)
				)
				(justify mirror)
			)
		)
		(duplicate_pad_numbers_are_jumpers no)
		(fp_rect
			(start 0.4318 0.9525)
			(end -0.4318 -0.9525)
			(stroke
				(width 0)
				(type default)
			)
			(fill no)
			(layer "B.CrtYd")
		)
		(fp_rect
			(start 0.4318 0.9525)
			(end -0.4318 -0.9525)
			(stroke
				(width 0)
				(type default)
			)
			(fill no)
			(layer "B.Fab")
		)
		(pad "1" smd custom
			(at 0 -0.4445)
			(size 0.1524 0.1524)
			(layers "B.Cu" "B.Mask" "B.Paste")
			(net "P1V8_C")
			(options
				(clearance outline)
				(anchor circle)
			)
			(primitives
				(gr_poly
					(pts
						(arc
							(start 0.3048 0.2032)
							(mid 0.275042 0.275042)
							(end 0.2032 0.3048)
						)
						(arc
							(start -0.2032 0.3048)
							(mid -0.275042 0.275042)
							(end -0.3048 0.2032)
						)
						(arc
							(start -0.3048 -0.2032)
							(mid -0.275042 -0.275042)
							(end -0.2032 -0.3048)
						)
						(arc
							(start 0.2032 -0.3048)
							(mid 0.275042 -0.275042)
							(end 0.3048 -0.2032)
						)
					)
					(width 0)
					(fill yes)
				)
			)
		)
		(pad "2" smd custom
			(at 0 0.4445)
			(size 0.1524 0.1524)
			(layers "B.Cu" "B.Mask" "B.Paste")
			(net "GND")
			(options
				(clearance outline)
				(anchor circle)
			)
			(primitives
				(gr_poly
					(pts
						(arc
							(start 0.3048 0.2032)
							(mid 0.275042 0.275042)
							(end 0.2032 0.3048)
						)
						(arc
							(start -0.2032 0.3048)
							(mid -0.275042 0.275042)
							(end -0.3048 0.2032)
						)
						(arc
							(start -0.3048 -0.2032)
							(mid -0.275042 -0.275042)
							(end -0.2032 -0.3048)
						)
						(arc
							(start 0.2032 -0.3048)
							(mid 0.275042 -0.275042)
							(end 0.3048 -0.2032)
						)
					)
					(width 0)
					(fill yes)
				)
			)
		)
	)
	(footprint ""
		(layer "B.Cu")
		(at 77.089 -22.352 90)
		(property "Reference" "SQ18"
			(at 0 0 90)
			(layer "B.SilkS")
			(hide yes)
			(effects
				(font
					(size 1.27 1.27)
				)
				(justify mirror)
			)
		)
		(property "Value" "2N7002A-7-GP"
			(at -0.127 -8.9662 90)
			(unlocked yes)
			(layer "B.Fab")
			(hide yes)
			(effects
				(font
					(size 1.016 1.016)
					(thickness 0.1524)
				)
				(justify mirror)
			)
		)
		(property "Device Type" "SOT23DGS2D4H48"
			(at -0.127 -10.4902 90)
			(unlocked yes)
			(layer "B.Fab")
			(hide yes)
			(effects
				(font
					(size 1.016 1.016)
					(thickness 0.1524)
				)
				(justify mirror)
			)
		)
		(duplicate_pad_numbers_are_jumpers no)
		(fp_line
			(start 1.651 -1.778)
			(end 1.651 1.778)
			(stroke
				(width 0.1524)
				(type default)
			)
			(layer "B.SilkS")
		)
		(fp_line
			(start -1.651 -1.778)
			(end 1.651 -1.778)
			(stroke
				(width 0.1524)
				(type default)
			)
			(layer "B.SilkS")
		)
		(fp_line
			(start 1.651 1.778)
			(end -1.651 1.778)
			(stroke
				(width 0.1524)
				(type default)
			)
			(layer "B.SilkS")
		)
		(fp_line
			(start -1.651 1.778)
			(end -1.651 -1.778)
			(stroke
				(width 0.1524)
				(type default)
			)
			(layer "B.SilkS")
		)
		(fp_poly
			(pts
				(xy 1.778 1.8796) (xy 1.778 -1.8796) (xy -1.778 -1.8796) (xy -1.778 1.8796)
			)
			(stroke
				(width 0)
				(type default)
			)
			(fill no)
			(layer "B.CrtYd")
		)
		(fp_poly
			(pts
				(xy 1.778 1.8796) (xy 1.778 -1.8796) (xy -1.778 -1.8796) (xy -1.778 1.8796)
			)
			(stroke
				(width 0)
				(type default)
			)
			(fill no)
			(layer "B.Fab")
		)
		(pad "D" smd custom
			(at 0 -0.9525 270)
			(size 0.1905 0.1905)
			(layers "B.Cu" "B.Mask" "B.Paste")
			(net "P3V3_STBY_R9")
			(options
				(clearance outline)
				(anchor circle)
			)
			(primitives
				(gr_poly
					(pts
						(arc
							(start -0.1778 -0.5715)
							(mid -0.321484 -0.511984)
							(end -0.381 -0.3683)
						)
						(arc
							(start -0.381 0.3683)
							(mid -0.321484 0.511984)
							(end -0.1778 0.5715)
						)
						(arc
							(start 0.1778 0.5715)
							(mid 0.321484 0.511984)
							(end 0.381 0.3683)
						)
						(arc
							(start 0.381 -0.3683)
							(mid 0.321484 -0.511984)
							(end 0.1778 -0.5715)
						)
					)
					(width 0)
					(fill yes)
				)
			)
		)
		(pad "G" smd custom
			(at 0.98425 0.9525 270)
			(size 0.1905 0.1905)
			(layers "B.Cu" "B.Mask" "B.Paste")
			(net "PG_STAT_P0V955_C")
			(options
				(clearance outline)
				(anchor circle)
			)
			(primitives
				(gr_poly
					(pts
						(arc
							(start -0.1778 -0.5715)
							(mid -0.321484 -0.511984)
							(end -0.381 -0.3683)
						)
						(arc
							(start -0.381 0.3683)
							(mid -0.321484 0.511984)
							(end -0.1778 0.5715)
						)
						(arc
							(start 0.1778 0.5715)
							(mid 0.321484 0.511984)
							(end 0.381 0.3683)
						)
						(arc
							(start 0.381 -0.3683)
							(mid 0.321484 -0.511984)
							(end 0.1778 -0.5715)
						)
					)
					(width 0)
					(fill yes)
				)
			)
		)
		(pad "S" smd custom
			(at -0.98425 0.9525 270)
			(size 0.1905 0.1905)
			(layers "B.Cu" "B.Mask" "B.Paste")
			(net "GND")
			(options
				(clearance outline)
				(anchor circle)
			)
			(primitives
				(gr_poly
					(pts
						(arc
							(start -0.1778 -0.5715)
							(mid -0.321484 -0.511984)
							(end -0.381 -0.3683)
						)
						(arc
							(start -0.381 0.3683)
							(mid -0.321484 0.511984)
							(end -0.1778 0.5715)
						)
						(arc
							(start 0.1778 0.5715)
							(mid 0.321484 0.511984)
							(end 0.381 0.3683)
						)
						(arc
							(start 0.381 -0.3683)
							(mid 0.321484 -0.511984)
							(end 0.1778 -0.5715)
						)
					)
					(width 0)
					(fill yes)
				)
			)
		)
	)
	(footprint ""
		(layer "B.Cu")
		(at 256.159 -17.907 -90)
		(property "Reference" "C239"
			(at 0 0 90)
			(layer "B.SilkS")
			(hide yes)
			(effects
				(font
					(size 1.27 1.27)
				)
				(justify mirror)
			)
		)
		(property "Value" "SC1KP50V2KX-1GP"
			(at -1.1811 -2.7051 270)
			(unlocked yes)
			(layer "B.Fab")
			(hide yes)
			(effects
				(font
					(size 1.016 1.016)
					(thickness 0.1524)
				)
				(justify mirror)
			)
		)
		(property "Device Type" "C402H22"
			(at -1.1811 -4.2291 270)
			(unlocked yes)
			(layer "B.Fab")
			(hide yes)
			(effects
				(font
					(size 1.016 1.016)
					(thickness 0.1524)
				)
				(justify mirror)
			)
		)
		(duplicate_pad_numbers_are_jumpers no)
		(fp_rect
			(start 0.4318 0.9525)
			(end -0.4318 -0.9525)
			(stroke
				(width 0)
				(type default)
			)
			(fill no)
			(layer "B.CrtYd")
		)
		(fp_rect
			(start 0.4318 0.9525)
			(end -0.4318 -0.9525)
			(stroke
				(width 0)
				(type default)
			)
			(fill no)
			(layer "B.Fab")
		)
		(pad "1" smd custom
			(at 0 -0.4445 90)
			(size 0.1524 0.1524)
			(layers "B.Cu" "B.Mask" "B.Paste")
			(net "USB_OCS_N1")
			(options
				(clearance outline)
				(anchor circle)
			)
			(primitives
				(gr_poly
					(pts
						(arc
							(start 0.3048 0.2032)
							(mid 0.275042 0.275042)
							(end 0.2032 0.3048)
						)
						(arc
							(start -0.2032 0.3048)
							(mid -0.275042 0.275042)
							(end -0.3048 0.2032)
						)
						(arc
							(start -0.3048 -0.2032)
							(mid -0.275042 -0.275042)
							(end -0.2032 -0.3048)
						)
						(arc
							(start 0.2032 -0.3048)
							(mid 0.275042 -0.275042)
							(end 0.3048 -0.2032)
						)
					)
					(width 0)
					(fill yes)
				)
			)
		)
		(pad "2" smd custom
			(at 0 0.4445 90)
			(size 0.1524 0.1524)
			(layers "B.Cu" "B.Mask" "B.Paste")
			(net "GND")
			(options
				(clearance outline)
				(anchor circle)
			)
			(primitives
				(gr_poly
					(pts
						(arc
							(start 0.3048 0.2032)
							(mid 0.275042 0.275042)
							(end 0.2032 0.3048)
						)
						(arc
							(start -0.2032 0.3048)
							(mid -0.275042 0.275042)
							(end -0.3048 0.2032)
						)
						(arc
							(start -0.3048 -0.2032)
							(mid -0.275042 -0.275042)
							(end -0.2032 -0.3048)
						)
						(arc
							(start 0.2032 -0.3048)
							(mid 0.275042 -0.275042)
							(end 0.3048 -0.2032)
						)
					)
					(width 0)
					(fill yes)
				)
			)
		)
	)
	(footprint ""
		(layer "B.Cu")
		(at 294.7162 -203.962 180)
		(property "Reference" "C173"
			(at 0 0 0)
			(layer "B.SilkS")
			(hide yes)
			(effects
				(font
					(size 1.27 1.27)
				)
				(justify mirror)
			)
		)
		(property "Value" "SCD1U16V2KX-3GP"
			(at -1.1811 -2.7051 180)
			(unlocked yes)
			(layer "B.Fab")
			(hide yes)
			(effects
				(font
					(size 1.016 1.016)
					(thickness 0.1524)
				)
				(justify mirror)
			)
		)
		(property "Device Type" "C402H22"
			(at -1.1811 -4.2291 180)
			(unlocked yes)
			(layer "B.Fab")
			(hide yes)
			(effects
				(font
					(size 1.016 1.016)
					(thickness 0.1524)
				)
				(justify mirror)
			)
		)
		(duplicate_pad_numbers_are_jumpers no)
		(fp_rect
			(start 0.4318 0.9525)
			(end -0.4318 -0.9525)
			(stroke
				(width 0)
				(type default)
			)
			(fill no)
			(layer "B.CrtYd")
		)
		(fp_rect
			(start 0.4318 0.9525)
			(end -0.4318 -0.9525)
			(stroke
				(width 0)
				(type default)
			)
			(fill no)
			(layer "B.Fab")
		)
		(pad "1" smd custom
			(at 0 -0.4445)
			(size 0.1524 0.1524)
			(layers "B.Cu" "B.Mask" "B.Paste")
			(net "P1V53_STBY")
			(options
				(clearance outline)
				(anchor circle)
			)
			(primitives
				(gr_poly
					(pts
						(arc
							(start 0.3048 0.2032)
							(mid 0.275042 0.275042)
							(end 0.2032 0.3048)
						)
						(arc
							(start -0.2032 0.3048)
							(mid -0.275042 0.275042)
							(end -0.3048 0.2032)
						)
						(arc
							(start -0.3048 -0.2032)
							(mid -0.275042 -0.275042)
							(end -0.2032 -0.3048)
						)
						(arc
							(start 0.2032 -0.3048)
							(mid 0.275042 -0.275042)
							(end 0.3048 -0.2032)
						)
					)
					(width 0)
					(fill yes)
				)
			)
		)
		(pad "2" smd custom
			(at 0 0.4445)
			(size 0.1524 0.1524)
			(layers "B.Cu" "B.Mask" "B.Paste")
			(net "GND")
			(options
				(clearance outline)
				(anchor circle)
			)
			(primitives
				(gr_poly
					(pts
						(arc
							(start 0.3048 0.2032)
							(mid 0.275042 0.275042)
							(end 0.2032 0.3048)
						)
						(arc
							(start -0.2032 0.3048)
							(mid -0.275042 0.275042)
							(end -0.3048 0.2032)
						)
						(arc
							(start -0.3048 -0.2032)
							(mid -0.275042 -0.275042)
							(end -0.2032 -0.3048)
						)
						(arc
							(start 0.2032 -0.3048)
							(mid 0.275042 -0.275042)
							(end 0.3048 -0.2032)
						)
					)
					(width 0)
					(fill yes)
				)
			)
		)
	)
	(footprint ""
		(layer "B.Cu")
		(at 338.713318 -135.385048 90)
		(property "Reference" "R557"
			(at 0 0 90)
			(layer "B.SilkS")
			(hide yes)
			(effects
				(font
					(size 1.27 1.27)
				)
				(justify mirror)
			)
		)
		(property "Value" "0R3J-0-U-GP"
			(at 0.0254 -2.5146 90)
			(unlocked yes)
			(layer "B.Fab")
			(hide yes)
			(effects
				(font
					(size 1.016 1.016)
					(thickness 0.1524)
				)
				(justify mirror)
			)
		)
		(property "Device Type" "R603H22"
			(at 0.0254 -4.0386 90)
			(unlocked yes)
			(layer "B.Fab")
			(hide yes)
			(effects
				(font
					(size 1.016 1.016)
					(thickness 0.1524)
				)
				(justify mirror)
			)
		)
		(duplicate_pad_numbers_are_jumpers no)
		(fp_line
			(start 0.4826 0)
			(end 0.2032 0)
			(stroke
				(width 0.2032)
				(type default)
			)
			(layer "B.SilkS")
		)
		(fp_line
			(start -0.2032 0)
			(end -0.4826 0)
			(stroke
				(width 0.2032)
				(type default)
			)
			(layer "B.SilkS")
		)
		(fp_rect
			(start 0.5842 1.3335)
			(end -0.5842 -1.3335)
			(stroke
				(width 0)
				(type default)
			)
			(fill no)
			(layer "B.CrtYd")
		)
		(fp_rect
			(start 0.5842 1.3335)
			(end -0.5842 -1.3335)
			(stroke
				(width 0)
				(type default)
			)
			(fill no)
			(layer "B.Fab")
		)
		(pad "1" smd custom
			(at 0 -0.762 270)
			(size 0.2159 0.2159)
			(layers "B.Cu" "B.Mask" "B.Paste")
			(net "USB_P0_DN_R")
			(options
				(clearance outline)
				(anchor circle)
			)
			(primitives
				(gr_poly
					(pts
						(arc
							(start -0.3302 0.4318)
							(mid -0.402042 0.402042)
							(end -0.4318 0.3302)
						)
						(arc
							(start -0.4318 -0.3302)
							(mid -0.402042 -0.402042)
							(end -0.3302 -0.4318)
						)
						(arc
							(start 0.3302 -0.4318)
							(mid 0.402042 -0.402042)
							(end 0.4318 -0.3302)
						)
						(arc
							(start 0.4318 0.3302)
							(mid 0.402042 0.402042)
							(end 0.3302 0.4318)
						)
					)
					(width 0)
					(fill yes)
				)
			)
		)
		(pad "2" smd custom
			(at 0 0.762 270)
			(size 0.2159 0.2159)
			(layers "B.Cu" "B.Mask" "B.Paste")
			(net "USB_P0_DN")
			(options
				(clearance outline)
				(anchor circle)
			)
			(primitives
				(gr_poly
					(pts
						(arc
							(start -0.3302 0.4318)
							(mid -0.402042 0.402042)
							(end -0.4318 0.3302)
						)
						(arc
							(start -0.4318 -0.3302)
							(mid -0.402042 -0.402042)
							(end -0.3302 -0.4318)
						)
						(arc
							(start 0.3302 -0.4318)
							(mid 0.402042 -0.402042)
							(end 0.4318 -0.3302)
						)
						(arc
							(start 0.4318 0.3302)
							(mid 0.402042 0.402042)
							(end 0.3302 0.4318)
						)
					)
					(width 0)
					(fill yes)
				)
			)
		)
	)
	(footprint ""
		(layer "B.Cu")
		(at 127.90297 -101.727 90)
		(property "Reference" "SC1183"
			(at 0 0 90)
			(layer "B.SilkS")
			(hide yes)
			(effects
				(font
					(size 1.27 1.27)
				)
				(justify mirror)
			)
		)
		(property "Value" "SC22U6D3V5MX-2GP"
			(at 0.0762 -6.1214 90)
			(unlocked yes)
			(layer "B.Fab")
			(hide yes)
			(effects
				(font
					(size 1.016 1.016)
					(thickness 0.1524)
				)
				(justify mirror)
			)
		)
		(property "Device Type" "C805H58"
			(at 0.0762 -8.1534 90)
			(unlocked yes)
			(layer "B.Fab")
			(hide yes)
			(effects
				(font
					(size 1.016 1.016)
					(thickness 0.1524)
				)
				(justify mirror)
			)
		)
		(duplicate_pad_numbers_are_jumpers no)
		(fp_line
			(start -0.635 0)
			(end 0.635 0)
			(stroke
				(width 0.508)
				(type default)
			)
			(layer "B.SilkS")
		)
		(fp_rect
			(start 0.9652 1.778)
			(end -0.9652 -1.778)
			(stroke
				(width 0)
				(type default)
			)
			(fill no)
			(layer "B.CrtYd")
		)
		(fp_poly
			(pts
				(xy 0.9652 -1.778) (xy -0.9652 -1.778) (xy -0.9652 1.778) (xy 0.9652 1.778)
			)
			(stroke
				(width 0)
				(type default)
			)
			(fill no)
			(layer "B.Fab")
		)
		(pad "1" smd rect
			(at 0 -0.9652 270)
			(size 1.397 1.143)
			(layers "B.Cu" "B.Mask" "B.Paste")
			(net "GB_VDDA")
		)
		(pad "2" smd rect
			(at 0 0.9652 270)
			(size 1.397 1.143)
			(layers "B.Cu" "B.Mask" "B.Paste")
			(net "GND")
		)
	)
	(footprint ""
		(layer "B.Cu")
		(at 34.494216 -232.33888)
		(property "Reference" "R511"
			(at 0 0 0)
			(layer "B.SilkS")
			(hide yes)
			(effects
				(font
					(size 1.27 1.27)
				)
				(justify mirror)
			)
		)
		(property "Value" "0R2J-2-GP"
			(at -0.064008 -3.993896 0)
			(unlocked yes)
			(layer "B.Fab")
			(hide yes)
			(effects
				(font
					(size 1.016 1.016)
					(thickness 0.1524)
				)
				(justify mirror)
			)
		)
		(property "Device Type" "R402H16"
			(at -0.064008 -5.517896 0)
			(unlocked yes)
			(layer "B.Fab")
			(hide yes)
			(effects
				(font
					(size 1.016 1.016)
					(thickness 0.1524)
				)
				(justify mirror)
			)
		)
		(duplicate_pad_numbers_are_jumpers no)
		(fp_line
			(start -0.508 -0.9398)
			(end 0.508 -0.9398)
			(stroke
				(width 0.1524)
				(type default)
			)
			(layer "B.SilkS")
		)
		(fp_line
			(start 0.508 -0.9398)
			(end 0.508 0.9398)
			(stroke
				(width 0.1524)
				(type default)
			)
			(layer "B.SilkS")
		)
		(fp_rect
			(start 0.508 0.9398)
			(end -0.508 -0.9398)
			(stroke
				(width 0)
				(type default)
			)
			(fill no)
			(layer "B.CrtYd")
		)
		(fp_rect
			(start 0.508 0.9398)
			(end -0.508 -0.9398)
			(stroke
				(width 0)
				(type default)
			)
			(fill no)
			(layer "B.Fab")
		)
		(pad "1" smd custom
			(at 0 -0.4445 180)
			(size 0.1397 0.1397)
			(layers "B.Cu" "B.Mask" "B.Paste")
			(net "SAS_HDD_PWR9_PCIE")
			(options
				(clearance outline)
				(anchor circle)
			)
			(primitives
				(gr_poly
					(pts
						(arc
							(start -0.1778 0.2794)
							(mid -0.249642 0.249642)
							(end -0.2794 0.1778)
						)
						(arc
							(start -0.2794 -0.1778)
							(mid -0.249642 -0.249642)
							(end -0.1778 -0.2794)
						)
						(arc
							(start 0.1778 -0.2794)
							(mid 0.249642 -0.249642)
							(end 0.2794 -0.1778)
						)
						(arc
							(start 0.2794 0.1778)
							(mid 0.249642 0.249642)
							(end 0.1778 0.2794)
						)
					)
					(width 0)
					(fill yes)
				)
			)
		)
		(pad "2" smd custom
			(at 0 0.4445 180)
			(size 0.1397 0.1397)
			(layers "B.Cu" "B.Mask" "B.Paste")
			(net "SAS_HDD_PWR9")
			(options
				(clearance outline)
				(anchor circle)
			)
			(primitives
				(gr_poly
					(pts
						(arc
							(start -0.1778 0.2794)
							(mid -0.249642 0.249642)
							(end -0.2794 0.1778)
						)
						(arc
							(start -0.2794 -0.1778)
							(mid -0.249642 -0.249642)
							(end -0.1778 -0.2794)
						)
						(arc
							(start 0.1778 -0.2794)
							(mid 0.249642 -0.249642)
							(end 0.2794 -0.1778)
						)
						(arc
							(start 0.2794 0.1778)
							(mid 0.249642 0.249642)
							(end 0.1778 0.2794)
						)
					)
					(width 0)
					(fill yes)
				)
			)
		)
	)
)
